FILE_TYPE = CONNECTIVITY;
{Allegro Design Entry HDL 16.6-p007 (v16-6-112F) 10/10/2012}
"PAGE_NUMBER" = 221;
0"NC";
1"GND\g";
2"GND\g";
3"GND\g";
4"GND\g";
5"GND\g";
6"GND\g";
7"GND\g";
8"GND\g";
9"P3V3\g";
10"PVTT_ABC\g";
11"GND\g";
12"PVTT_ABC\g";
13"GND\g";
14"P3V3\g";
15"PVDDQ_ABC\g";
16"PWRGD_PVDDQ_ABC_R";
17"VR_PVTT_ABC_VREF";
18"VR_PVTT_ABC_BIAS";
19"FM_PVTT_ABC_EN_R";
20"PWRGD_PVTT_CPU0";
21"VR_PVTT_ABC_SNS";
22"VSENSE_PVDDQ_ABC_VTT";
23"PWRGD_PVTT_ABC_CPU0_R";
%"GND"
"1","(-650,-700)","0","mstr_symbols","I1";
;
HDL_POWER"GND"
BODY_TYPE"PLUMBING"
VOLTAGE"0.0V"
SIZE"1B"
CDS_LIB"mstr_symbols";
"A\NAC"1;
%"GND"
"1","(50,700)","0","mstr_symbols","I10";
;
HDL_POWER"GND"
BODY_TYPE"PLUMBING"
CDS_LIB"mstr_symbols"
VOLTAGE"0.0V"
SIZE"1B";
"A\NAC"2;
%"CAP"
"1","(50,925)","0","mstr_discrete","I11";
;
PART_NUMBER"E15431-003"
MATERIAL"X6S"
TOLERANCE"10%"
VOLTAGE"6.3V"
VALUE"4.7UF"
LOCATION"C6U12"
PACK_TYPE"0603"
CDS_SEC"1"
CDS_LOCATION"C6U12"
SEC"1"
SEC_TYPE"0603"
ROOM"VTT_ABC_PWR_VR"
CDS_LIB"mstr_discrete";
"A"
$PN"1"22;
"B"
$PN"2"2;
%"GND"
"1","(200,1175)","0","mstr_symbols","I12";
;
HDL_POWER"GND"
BODY_TYPE"PLUMBING"
SIZE"1B"
CDS_LIB"mstr_symbols"
VOLTAGE"0.0V";
"A\NAC"3;
%"CAP"
"1","(200,1400)","0","mstr_discrete","I13";
;
TOLERANCE"10%"
MATERIAL"X6S"
PART_NUMBER"D97712-011"
PACK_TYPE"0402"
VOLTAGE"16V"
VALUE"1.0UF"
LOCATION"C4G15"
BOM_COST"MEM_VRD_VTT_ABC"
CDS_SEC"1"
$SEC"1"
CDS_LOCATION"C4G15"
ROOM"VTT_ABC_PWR_VR"
CDS_LIB"mstr_discrete";
"A"
$PN"1"18;
"B"
$PN"2"3;
%"RES"
"1","(-150,1675)","0","mstr_discrete","I14";
;
PACK_TYPE"0402"
MATERIAL"CHIP"
TOLERANCE"5%"
VALUE"0.0"
PART_NUMBER"G21497-005"
WATTAGE"1/16W"
LOCATION"R6U4"
CDS_SEC"1"
ROOM"VTT_ABC_PWR_VR"
SEC"1"
CDS_LOCATION"R6U4"
SEC_TYPE"0402"
BOM_COST"MEM_VRD_VTT_ABC"
CDS_LIB"mstr_discrete";
"B"
$PN"2"18;
"A"
$PN"1"14;
%"MIC5166"
"1","(1275,975)","0","mstr_vreg","I15";
;
PART_NUMBER"H55101-001"
LOCATION"EU4G3"
MATERIAL"IC"
CDS_SEC"1"
CDS_LIB"mstr_vreg"
CDS_LMAN_SYM_OUTLINE"-250,350,250,-350"
BOM_COST"MEM_VRD_VTT_ABC"
PACK_TYPE"DFN"
ROOM"VTT_ABC_PWR_VR"
SEC"1"
SEC_TYPE"DFN"
CDS_LOCATION"EU4G3";
"THPAD"
$PN"11"4;
"VTT"
$PN"9"12;
"PGND"
$PN"8"4;
"SNS"
$PN"6"21;
"VDDQ"
$PN"4"22;
"PG"
$PN"5"23;
"AGND"
$PN"3"4;
"BIAS"
$PN"2"18;
"VREF"
$PN"1"17;
"VIN"
$PN"10"15;
"EN"
$PN"7"19;
%"GND"
"1","(1725,500)","0","mstr_symbols","I16";
;
HDL_POWER"GND"
BODY_TYPE"PLUMBING"
SIZE"1B"
VOLTAGE"0.0V"
CDS_LIB"mstr_symbols";
"A\NAC"4;
%"GND"
"1","(-225,2025)","0","mstr_symbols","I17";
;
HDL_POWER"GND"
BODY_TYPE"PLUMBING"
VOLTAGE"0.0V"
CDS_LIB"mstr_symbols"
SIZE"1B"
ROOM"VTT_ABC_PWR_VR"
BOM_COST"MEM_VRD_VTT_ABC";
"A\NAC"5;
%"CAP"
"1","(-225,2250)","0","mstr_discrete","I18";
;
PACK_TYPE"0603LF"
PART_NUMBER"E15431-001"
MATERIAL"X6S"
TOLERANCE"20%"
VOLTAGE"4V"
VALUE"10UF"
LOCATION"C6U15"
CDS_SEC"1"
SEC"1"
SEC_TYPE"0603LF"
BOM_COST"MEM_VRD_VTT_ABC"
ROOM"VTT_ABC_PWR_VR"
CDS_LOCATION"C6U15"
CDS_LIB"mstr_discrete";
"A"
$PN"1"15;
"B"
$PN"2"5;
%"CAP"
"1","(200,2275)","0","mstr_discrete","I19";
;
LOCATION"C6U16"
PACK_TYPE"0603LF"
PART_NUMBER"E15431-001"
MATERIAL"X6S"
TOLERANCE"20%"
VOLTAGE"4V"
VALUE"10UF"
CDS_SEC"1"
SEC_TYPE"0603LF"
SEC"1"
BOM_COST"MEM_VRD_VTT_ABC"
CDS_LOCATION"C6U16"
ROOM"VTT_ABC_PWR_VR"
CDS_LIB"mstr_discrete";
"A"
$PN"1"15;
"B"
$PN"2"6;
%"CAP"
"1","(-650,-475)","2","mstr_discrete","I2";
;
PART_NUMBER"A36096-046"
VOLTAGE"50V"
TOLERANCE"10%"
VALUE"1000PF"
PACK_TYPE"0402LF"
MATERIAL"EMPTY"
LOCATION"C4G23"
CDS_SEC"1"
ROOM"VTT_ABC_PWR_VR"
SEC"1"
SEC_TYPE"0402LF"
BOM_COST"MEM_VRD_VTT_ABC"
CDS_LIB"mstr_discrete"
CDS_LOCATION"C4G23";
"A"
$PN"1"19;
"B"
$PN"2"1;
%"GND"
"1","(200,2025)","0","mstr_symbols","I20";
;
HDL_POWER"GND"
BODY_TYPE"PLUMBING"
SIZE"1B"
VOLTAGE"0.0V"
CDS_LIB"mstr_symbols"
ROOM"VTT_ABC_PWR_VR"
BOM_COST"MEM_VRD_VTT_ABC";
"A\NAC"6;
%"GND"
"1","(2100,500)","0","mstr_symbols","I21";
;
HDL_POWER"GND"
BODY_TYPE"PLUMBING"
SIZE"1B"
VOLTAGE"0.0V"
CDS_LIB"mstr_symbols";
"A\NAC"7;
%"CAP"
"1","(2100,750)","0","mstr_discrete","I22";
;
PART_NUMBER"D97712-011"
PACK_TYPE"0402"
TOLERANCE"10%"
VALUE"1.0UF"
VOLTAGE"16V"
MATERIAL"X6S"
LOCATION"C4G16"
CDS_SEC"1"
SEC_TYPE"0402"
BOM_COST"MEM_VRD_VTT_ABC"
SEC"1"
ROOM"VTT_ABC_PWR_VR"
CDS_LOCATION"C4G16"
CDS_LIB"mstr_discrete";
"A"
$PN"1"17;
"B"
$PN"2"7;
%"GND"
"1","(3700,525)","0","mstr_symbols","I23";
;
HDL_POWER"GND"
BODY_TYPE"PLUMBING"
VOLTAGE"0.0V"
SIZE"1B"
CDS_LIB"mstr_symbols";
"A\NAC"8;
%"CAP"
"1","(3700,950)","0","mstr_discrete","I24";
;
GROUP"PWR_MLCC_CAP"
VALUE"22UF"
LOCATION"C4G24"
VOLTAGE"4V"
PACK_TYPE"0805LF"
MATERIAL"X6S"
TOLERANCE"20%"
PART_NUMBER"C95333-002"
CDS_SEC"1"
SEC_TYPE"0805LF"
ROOM"VTT_ABC_PWR_VR"
CDS_LOCATION"C4G24"
SEC"1"
CDS_LIB"mstr_discrete"
BOM_COST"MEM_VRD_VTT_ABC";
"A"
$PN"1"12;
"B"
$PN"2"8;
%"RES"
"2","(3225,2000)","0","mstr_discrete","I25";
;
MATERIAL"CHIP"
WATTAGE"1/16W"
TOLERANCE"1%"
VALUE"10.0K"
LOCATION"R4G18"
PACK_TYPE"0402"
PART_NUMBER"G21796-016"
CDS_SEC"1"
CDS_LIB"mstr_discrete"
CDS_LOCATION"R4G18"
ROOM"VTT_ABC_PWR_VR"
SEC"1"
SEC_TYPE"0402"
BOM_COST"MEM_VRD_VTT_ABC";
"A"
$PN"1"9;
"B"
$PN"2"23;
%"P3V3"
"1","(3225,2200)","0","mstr_symbols","I26";
;
HDL_POWER"P3V3"
BODY_TYPE"PLUMBING"
CDS_LIB"mstr_symbols"
SIZE"1B"
VOLTAGE"3.3V";
"G\NAC"9;
%"PVTT_ABC"
"1","(3325,3650)","0","mstr_symbols","I28";
;
HDL_POWER"PVTT_ABC"
BODY_TYPE"PLUMBING"
ROOM"VTT_ABC_PWR_VR"
BOM_COST"MEM_VRD_PVDDQ_AB"
CDS_LIB"mstr_symbols"
VOLTAGE"0.6V";
"G\NAC"10;
%"CAP"
"1","(3850,1525)","0","mstr_discrete","I30";
;
PART_NUMBER"A36096-046"
TOLERANCE"10%"
LOCATION"C4G14"
MATERIAL"X7R"
VOLTAGE"50V"
VALUE"1000PF"
PACK_TYPE"0402LF"
CDS_SEC"1"
CDS_LIB"mstr_discrete"
CDS_LOCATION"C4G14"
ROOM"VTT_ABC_PWR_VR"
BOM_COST"MEM_VRD_VTT_ABC"
SEC_TYPE"0402LF"
SEC"1";
"A"
$PN"1"23;
"B"
$PN"2"11;
%"GND"
"1","(3850,1300)","0","mstr_symbols","I32";
;
HDL_POWER"GND"
BODY_TYPE"PLUMBING"
VOLTAGE"0.0V"
CDS_LIB"mstr_symbols"
SIZE"1B";
"A\NAC"11;
%"RES"
"1","(4350,1725)","0","mstr_discrete","I33";
;
TOLERANCE"1%"
LOCATION"R4G19"
PART_NUMBER"G21796-074"
PACK_TYPE"0402"
VALUE"33.2"
MATERIAL"CHIP"
WATTAGE"1/16W"
CDS_SEC"1"
SEC"1"
CDS_LIB"mstr_discrete"
SEC_TYPE"0402"
CDS_LOCATION"R4G19";
"B"
$PN"2"20;
"A"
$PN"1"23;
%"PVTT_ABC"
"1","(5250,1500)","0","mstr_symbols","I34";
;
HDL_POWER"PVTT_ABC"
BODY_TYPE"PLUMBING"
CDS_LIB"mstr_symbols"
VOLTAGE"0.6V";
"G\NAC"12;
%"GND"
"1","(3325,2825)","0","mstr_symbols","I36";
;
HDL_POWER"GND"
BODY_TYPE"PLUMBING"
CDS_LIB"mstr_symbols"
VOLTAGE"0.0V"
SIZE"1B"
BOM_COST"MEM_VRD_PVDDQ_AB"
ROOM"VTT_ABC_PWR_VR";
"A\NAC"13;
%"RES"
"1","(-800,50)","0","mstr_discrete","I4";
;
PART_NUMBER"G21497-005"
PACK_TYPE"0402"
VALUE"0.0"
TOLERANCE"5%"
MATERIAL"CHIP"
WATTAGE"1/16W"
LOCATION"R4G23"
CDS_SEC"1"
BOM_COST"MEM_VRD_VTT_ABC"
SEC_TYPE"0402"
SEC"1"
ROOM"VTT_ABC_PWR_VR"
CDS_LIB"mstr_discrete"
CDS_LOCATION"R4G23";
"B"
$PN"2"19;
"A"
$PN"1"16;
%"CAP_A"
"1","(4075,3300)","0","dev_discrete","I40";
;
PACK_TYPE"0603V"
VOLTAGE"4V"
TOLERANCE"20%"
MATERIAL"X5R"
PART_NUMBER"602433-106"
VALUE"47UF"
LOCATION"C5T3"
GROUP"PWR_MLCC_CAP"
CDS_SEC"1"
SEC_TYPE"0603V"
SEC"1"
CDS_LOCATION"C5T3"
CDS_LIB"dev_discrete";
"B"
$PN"2"13;
"A"
$PN"1"10;
%"CAP"
"1","(4425,975)","0","mstr_discrete","I44";
;
PART_NUMBER"602433-112"
GROUP"PWR_MLCC_CAP"
LOCATION"C6W11"
VALUE"100UF"
NEW_MATERIAL"X6S"
TOLERANCE"20%"
VOLTAGE"4V"
PACK_TYPE"0805"
NEW_PN"078.1071T.M002"
CDS_LOCATION"C6W11"
CDS_SEC"1"
CDS_LIB"mstr_discrete"
BOM_COST"MEM_VRD_PVDDQ_CD"
ROOM"VDDQ_ABC_PWR_VR"
SEC_TYPE"0805"
SEC"1"
MATERIAL"X5R";
"A"
$PN"1"12;
"B"
$PN"2"8;
%"CAP"
"1","(3325,3300)","0","mstr_discrete","I45";
;
GROUP"PWR_MLCC_CAP"
NEW_PN"078.1071T.M002"
PACK_TYPE"0805"
NEW_MATERIAL"X6S"
TOLERANCE"20%"
VOLTAGE"4V"
VALUE"100UF"
PART_NUMBER"602433-112"
LOCATION"C5U12"
CDS_LOCATION"C5U12"
CDS_SEC"1"
CDS_LIB"mstr_discrete"
BOM_COST"MEM_VRD_PVDDQ_CD"
ROOM"VDDQ_ABC_PWR_VR"
SEC_TYPE"0805"
SEC"1"
MATERIAL"X5R";
"A"
$PN"1"10;
"B"
$PN"2"13;
%"CAP"
"1","(3675,3300)","0","mstr_discrete","I46";
;
NEW_MATERIAL"X6S"
VALUE"100UF"
PACK_TYPE"0805"
PART_NUMBER"602433-112"
LOCATION"C5U16"
TOLERANCE"20%"
VOLTAGE"4V"
GROUP"PWR_MLCC_CAP"
NEW_PN"078.1071T.M002"
CDS_LOCATION"C5U16"
CDS_SEC"1"
CDS_LIB"mstr_discrete"
BOM_COST"MEM_VRD_PVDDQ_CD"
ROOM"VDDQ_ABC_PWR_VR"
SEC_TYPE"0805"
SEC"1"
MATERIAL"X5R";
"A"
$PN"1"10;
"B"
$PN"2"13;
%"RES"
"2","(-600,575)","2","mstr_discrete","I5";
;
PACK_TYPE"0402"
PART_NUMBER"G21796-021"
MATERIAL"EMPTY"
WATTAGE"1/16W"
TOLERANCE"1%"
VALUE"1.0M"
LOCATION"R6U15"
CDS_SEC"1"
ROOM"VTT_ABC_PWR_VR"
CDS_LOCATION"R6U15"
SEC"1"
BOM_COST"MEM_VRD_VTT_ABC"
SEC_TYPE"0402"
CDS_LIB"mstr_discrete";
"A"
$PN"1"14;
"B"
$PN"2"19;
%"RES"
"2","(-1050,1450)","1","mstr_discrete","I6";
;
PART_NUMBER"G21497-005"
WATTAGE"1/16W"
VALUE"0.0"
TOLERANCE"5%"
LOCATION"R6U5"
PACK_TYPE"0402"
CDS_SEC"1"
SEC_TYPE"0402"
BOM_COST"MEM_VRD_VTT_ABC"
SEC"1"
CDS_LOCATION"R6U5"
NO_XNET_CONNECTION"1"
ROOM"VTT_ABC_PWR_VR"
MATERIAL"CHIP"
CDS_LIB"mstr_discrete";
"A"
$PN"1"15;
"B"
$PN"2"22;
%"P3V3"
"1","(-825,1975)","0","mstr_symbols","I7";
;
HDL_POWER"P3V3"
BODY_TYPE"PLUMBING"
CDS_LIB"mstr_symbols"
SIZE"1B"
VOLTAGE"3.3V";
"G\NAC"14;
%"PVDDQ_ABC"
"1","(-1700,2700)","0","mstr_symbols","I8";
;
HDL_POWER"PVDDQ_ABC"
BODY_TYPE"PLUMBING"
CDS_LIB"mstr_symbols"
VOLTAGE"1.2V";
"G\NAC"15;
%"SHUNT"
"1","(4700,-75)","0","mstr_misc","I9";
;
LOCATION"SH5U1"
PART_NUMBER"N_A"
CDS_SEC"1"
CDS_LOCATION"SH5U1"
SEC_TYPE"SH0201"
SEC"1"
CDS_LIB"mstr_misc"
MATERIAL"EMPTY"
PACK_TYPE"SH0201"
PIN_SHORT"A:B";
"A"
$PN"1"21;
"B"
$PN"2"12;
END.
